FILE_TYPE = MACRO_DRAWING;
SET COLOR_WIRE YELLOW;
SET COLOR_PROP ORANGE;
SET COLOR_DOT WHITE;
SET COLOR_ARC YELLOW;
SET COLOR_BODY GREEN;
SET COLOR_NOTE PURPLE;
SET PROP_DISPLAY VALUE;
SET PAGE_NUMBER P131;
FORCEADD QUANTA_TITLE_BLOCK_C..1
(0 0);
FORCEPROP 1 LAST CUSTOM_TXT_CDS <NAME_2>
J 0
(-3175 50);
FORCEPROP 1 LAST CUSTOM_TXT_CDS <NAME_1>
J 0
(-3175 175);
FORCEPROP 1 LAST CUSTOM_TXT_CDS <Q_NUMBER>
J 0
(-1403 103);
DISPLAY 1.212766 (-1403 103);
FORCEPROP 1 LAST CUSTOM_TXT_CDS <Q_PROJ>
J 0
(-2382 102);
DISPLAY 1.212766 (-2382 102);
FORCEPROP 1 LAST CUSTOM_TXT_CDS <Q_REV>
J 0
(-184 103);
DISPLAY 1.212766 (-184 103);
FORCEPROP 1 LAST CUSTOM_TXT_CDS <CON_LAST_MODIFIED>
J 0
(-1885 15);
DISPLAY 0.978723 (-1885 15);
FORCEPROP 1 LAST CUSTOM_TXT_CDS <CON_PAGE_NUM> OF <CON_TOTAL_PAGES>
J 0
(-446 18);
DISPLAY 0.978723 (-446 18);
FORCEPROP 1 LAST Q_TITLE SMBUS MUX
J 0
(-9300 50);
DISPLAY 2.446809 (-9300 50);
PAINT GREEN (-9300 50);
FORCEPROP 1 LAST Q_DEPT BU9
J 1
(-3763 49);
DISPLAY 1.957447 (-3763 49);
PAINT GREEN (-3763 49);
FORCEPROP 2 LAST CDS_LIB pure_quanta
J 0
(0 0);
DISPLAY INVISIBLE (0 0);
FORCEPROP 1 LAST CDS_LMAN_SYM_OUTLINE -9475,6775,100,-125
J 0
(0 0);
DISPLAY 0.468085 (0 0);
PAINT GREEN (0 0);
DISPLAY INVISIBLE (0 0);
FORCEPROP 2 LAST PAGE_BORDER TRUE
J 0
(-7890 5250);
DISPLAY 0.638298 (-7890 5250);
PAINT PINK (-7890 5250);
DISPLAY INVISIBLE (-7890 5250);
FORCEPROP 1 LAST COMMENT_BODY TRUE
J 0
(12 -13);
DISPLAY 0.978723 (12 -13);
PAINT GREEN (12 -13);
DISPLAY INVISIBLE (12 -13);
FORCEPROP 2 LAST CDS_XR_PAGE_TITLE CR-131 : @T6G_MB_LIB.T6G(SCH_1):PAGE131
J 0
(-7890 5250);
DISPLAY 0.638298 (-7890 5250);
PAINT PINK (-7890 5250);
DISPLAY INVISIBLE (-7890 5250);
FORCEPROP 2 LAST CUSTOM_TXT_CDS <XR_PAGE_TITLE>
J 0
(-7890 5250);
DISPLAY 0.638298 (-7890 5250);
PAINT PINK (-7890 5250);
DISPLAY INVISIBLE (-7890 5250);
FORCEPROP 0 LAST CDS_CON_LAST_MODIFIED Wed Mar 09 18:33:09 2022
J 0
(-1885 15);
DISPLAY INVISIBLE (-1885 15);
QUIT
